(kicad_pcb
	(version 20260206)
	(generator "pcbnew")
	(generator_version "10.0")
	(general
		(thickness 1.6)
		(legacy_teardrops no)
	)
	(paper "A4")
	(title_block
		(title "03242023_DA0F0TMBIJ0_F0T_Motherboard_J_brd_V01_OCP.brd")
		(comment 1 "Grand Teton / footprint 1682 of 6105 (U1), pads 4652-4677 of 4677")
	)
	(layers
		(0 "F.Cu" signal "TOP")
		(4 "In1.Cu" signal "GND")
		(6 "In2.Cu" signal "IN1")
		(8 "In3.Cu" signal "GND1")
		(10 "In4.Cu" signal "IN2")
		(12 "In5.Cu" signal "GND2")
		(14 "In6.Cu" signal "IN3")
		(16 "In7.Cu" signal "GND3")
		(18 "In8.Cu" signal "VCC")
		(20 "In9.Cu" signal "VCC1")
		(22 "In10.Cu" signal "GND4")
		(24 "In11.Cu" signal "IN4")
		(26 "In12.Cu" signal "GND5")
		(28 "In13.Cu" signal "IN5")
		(30 "In14.Cu" signal "GND6")
		(32 "In15.Cu" signal "IN6")
		(34 "In16.Cu" signal "GND7")
		(2 "B.Cu" signal "BOTTOM")
		(9 "F.Adhes" user "F.Adhesive")
		(11 "B.Adhes" user "B.Adhesive")
		(13 "F.Paste" user "Package Geometry/Pastemask Top")
		(15 "B.Paste" user "Package Geometry/Pastemask Bottom")
		(5 "F.SilkS" user "Ref Des/Silkscreen Top")
		(7 "B.SilkS" user "Ref Des/Silkscreen Bottom")
		(1 "F.Mask" user "Board Geometry/Soldermask Top")
		(3 "B.Mask" user "Board Geometry/Soldermask Bottom")
		(17 "Dwgs.User" user "User.Drawings")
		(19 "Cmts.User" user "User.Comments")
		(21 "Eco1.User" user "User.Eco1")
		(23 "Eco2.User" user "User.Eco2")
		(25 "Edge.Cuts" user "Board Geometry/Outline")
		(27 "Margin" user)
		(31 "F.CrtYd" user "Package Geometry/Place Bound Top")
		(29 "B.CrtYd" user "Package Geometry/Place Bound Bottom")
		(35 "F.Fab" user "Ref Des/Assembly Top")
		(33 "B.Fab" user "Ref Des/Assembly Bottom")
	)
	(footprint ""
		(layer "F.Cu")
		(at 111.93018 -251.76988 90)
		(property "Reference" "U1"
			(at -74.913236 41.548812 0)
			(unlocked yes)
			(layer "F.SilkS")
			(effects
				(font
					(size 1.6002 1.1938)
					(thickness 0.1524)
				)
				(justify left)
			)
		)
		(property "Value" ""
			(at 0 0 90)
			(layer "F.Fab")
			(effects
				(font
					(size 1.27 1.27)
				)
			)
		)
		(duplicate_pad_numbers_are_jumpers no)
		(pad "Y40" smd circle
			(at -5.68325 -18.146268 270)
			(size 0.4318 0.4318)
			(layers "F.Cu" "F.Mask" "F.Paste")
			(net "M_C_CPU1_SB_CA<5>")
		)
		(pad "Y42" smd circle
			(at -4.055618 -18.146268 270)
			(size 0.4318 0.4318)
			(layers "F.Cu" "F.Mask" "F.Paste")
			(net "GND")
		)
		(pad "Y44" smd circle
			(at -2.427732 -18.146268 270)
			(size 0.4318 0.4318)
			(layers "F.Cu" "F.Mask" "F.Paste")
			(net "M_B_CPU1_SA_CA<6>")
		)
		(pad "Y47" smd circle
			(at 1.613916 -18.036286 270)
			(size 0.4318 0.4318)
			(layers "F.Cu" "F.Mask" "F.Paste")
			(net "M_C_CPU1_SB_CA<1>")
		)
		(pad "Y49" smd circle
			(at 3.241802 -18.036286 270)
			(size 0.4318 0.4318)
			(layers "F.Cu" "F.Mask" "F.Paste")
			(net "GND")
		)
		(pad "Y51" smd circle
			(at 4.869434 -18.036286 270)
			(size 0.4318 0.4318)
			(layers "F.Cu" "F.Mask" "F.Paste")
			(net "M_C_CPU1_SA_CA<3>")
		)
		(pad "Y53" smd circle
			(at 6.49732 -18.036286 270)
			(size 0.4318 0.4318)
			(layers "F.Cu" "F.Mask" "F.Paste")
			(net "M_C_CPU1_SA_CS_N<3>")
		)
		(pad "Y55" smd circle
			(at 8.124952 -18.036286 270)
			(size 0.4318 0.4318)
			(layers "F.Cu" "F.Mask" "F.Paste")
			(net "GND")
		)
		(pad "Y57" smd circle
			(at 9.752838 -18.036286 270)
			(size 0.4318 0.4318)
			(layers "F.Cu" "F.Mask" "F.Paste")
			(net "M_B_CPU1_SA_DQ<30>")
		)
		(pad "Y59" smd circle
			(at 11.380724 -18.036286 270)
			(size 0.4318 0.4318)
			(layers "F.Cu" "F.Mask" "F.Paste")
			(net "M_B_CPU1_SA_DQ<27>")
		)
		(pad "Y61" smd circle
			(at 13.008356 -18.036286 270)
			(size 0.4318 0.4318)
			(layers "F.Cu" "F.Mask" "F.Paste")
			(net "GND")
		)
		(pad "Y63" smd circle
			(at 14.635988 -18.036286 270)
			(size 0.4318 0.4318)
			(layers "F.Cu" "F.Mask" "F.Paste")
			(net "M_C_CPU1_SA_DQ<22>")
		)
		(pad "Y65" smd circle
			(at 16.263874 -18.036286 270)
			(size 0.4318 0.4318)
			(layers "F.Cu" "F.Mask" "F.Paste")
			(net "M_C_CPU1_SA_DQ<19>")
		)
		(pad "Y67" smd circle
			(at 17.89176 -18.036286 270)
			(size 0.4318 0.4318)
			(layers "F.Cu" "F.Mask" "F.Paste")
			(net "GND")
		)
		(pad "Y69" smd circle
			(at 19.519392 -18.036286 270)
			(size 0.4318 0.4318)
			(layers "F.Cu" "F.Mask" "F.Paste")
			(net "M_B_CPU1_SA_DQ<14>")
		)
		(pad "Y71" smd circle
			(at 21.147278 -18.036286 270)
			(size 0.4318 0.4318)
			(layers "F.Cu" "F.Mask" "F.Paste")
			(net "M_B_CPU1_SA_DQ<11>")
		)
		(pad "Y73" smd circle
			(at 22.77491 -18.036286 270)
			(size 0.4318 0.4318)
			(layers "F.Cu" "F.Mask" "F.Paste")
			(net "GND")
		)
		(pad "Y75" smd circle
			(at 24.402796 -18.036286 270)
			(size 0.4318 0.4318)
			(layers "F.Cu" "F.Mask" "F.Paste")
			(net "M_C_CPU1_SA_DQ<6>")
		)
		(pad "Y77" smd circle
			(at 26.030682 -18.036286 270)
			(size 0.4318 0.4318)
			(layers "F.Cu" "F.Mask" "F.Paste")
			(net "M_C_CPU1_SA_DQ<3>")
		)
		(pad "Y79" smd circle
			(at 27.658314 -18.036286 270)
			(size 0.4318 0.4318)
			(layers "F.Cu" "F.Mask" "F.Paste")
			(net "PVCCFA_EHV_FIVRA_CPU1")
		)
		(pad "Y81" smd circle
			(at 29.2862 -18.036286 270)
			(size 0.4318 0.4318)
			(layers "F.Cu" "F.Mask" "F.Paste")
			(net "UPI_CPU1_CPU0_P2P2_DN<9>")
		)
		(pad "Y83" smd circle
			(at 30.914086 -18.036286 270)
			(size 0.4318 0.4318)
			(layers "F.Cu" "F.Mask" "F.Paste")
			(net "UPI_CPU1_CPU0_P2P2_DP<8>")
		)
		(pad "Y85" smd circle
			(at 32.541718 -18.036286 270)
			(size 0.4318 0.4318)
			(layers "F.Cu" "F.Mask" "F.Paste")
			(net "PVCCFA_EHV_FIVRA_CPU1")
		)
		(pad "Y87" smd circle
			(at 34.169604 -18.036286 270)
			(size 0.4318 0.4318)
			(layers "F.Cu" "F.Mask" "F.Paste")
			(net "P5E_CPU1_PE4_TX_DP<4>")
		)
		(pad "Y89" smd circle
			(at 35.797236 -18.036286 270)
			(size 0.4318 0.4318)
			(layers "F.Cu" "F.Mask" "F.Paste")
			(net "PVCCFA_EHV_FIVRA_CPU1")
		)
		(pad "Y91" smd oval
			(at 37.425122 -18.036286)
			(size 0.381 0.4826)
			(drill
				(offset 0 -0.0508)
			)
			(layers "F.Cu" "F.Mask" "F.Paste")
			(net "P5E_CPU1_PE4_RX_DN<4>")
		)
	)
)
